# S9S_MB_2U (Grand Teton) — schematic netlist excerpt (pin names and nets, part order shuffled) for the footprints in the layout excerpt that follows; sources: Cadence DE-HDL packaged netlist, KiCad conversion of 03242023_DA0F0TMBIJ0_F0T_Motherboard_J_brd_V01_OCP.brd

R4293  Q_RES  100 1% CHIP  pkg 0402LF  page 122 : A = H_CPU0_MEMHOT_IN_LVC1_R1_N ; B = H_CPU0_MEMHOT_IN_LVC1_N
R3613  Q_RES  4.7K 1% EMPTY  pkg 0402LF  page 172 : A = GND ; B = INA230_5_A0

(kicad_pcb
	(version 20260206)
	(generator "pcbnew")
	(generator_version "10.0")
	(general
		(thickness 1.6)
		(legacy_teardrops no)
	)
	(paper "A4")
	(title_block
		(title "03242023_DA0F0TMBIJ0_F0T_Motherboard_J_brd_V01_OCP.brd")
		(comment 1 "Grand Teton / footprints 3338-3339 of 6105")
	)
	(layers
		(0 "F.Cu" signal "TOP")
		(4 "In1.Cu" signal "GND")
		(6 "In2.Cu" signal "IN1")
		(8 "In3.Cu" signal "GND1")
		(10 "In4.Cu" signal "IN2")
		(12 "In5.Cu" signal "GND2")
		(14 "In6.Cu" signal "IN3")
		(16 "In7.Cu" signal "GND3")
		(18 "In8.Cu" signal "VCC")
		(20 "In9.Cu" signal "VCC1")
		(22 "In10.Cu" signal "GND4")
		(24 "In11.Cu" signal "IN4")
		(26 "In12.Cu" signal "GND5")
		(28 "In13.Cu" signal "IN5")
		(30 "In14.Cu" signal "GND6")
		(32 "In15.Cu" signal "IN6")
		(34 "In16.Cu" signal "GND7")
		(2 "B.Cu" signal "BOTTOM")
		(9 "F.Adhes" user "F.Adhesive")
		(11 "B.Adhes" user "B.Adhesive")
		(13 "F.Paste" user "Package Geometry/Pastemask Top")
		(15 "B.Paste" user "Package Geometry/Pastemask Bottom")
		(5 "F.SilkS" user "Ref Des/Silkscreen Top")
		(7 "B.SilkS" user "Ref Des/Silkscreen Bottom")
		(1 "F.Mask" user "Board Geometry/Soldermask Top")
		(3 "B.Mask" user "Board Geometry/Soldermask Bottom")
		(17 "Dwgs.User" user "User.Drawings")
		(19 "Cmts.User" user "User.Comments")
		(21 "Eco1.User" user "User.Eco1")
		(23 "Eco2.User" user "User.Eco2")
		(25 "Edge.Cuts" user "Board Geometry/Outline")
		(27 "Margin" user)
		(31 "F.CrtYd" user "Package Geometry/Place Bound Top")
		(29 "B.CrtYd" user "Package Geometry/Place Bound Bottom")
		(35 "F.Fab" user "Ref Des/Assembly Top")
		(33 "B.Fab" user "Ref Des/Assembly Bottom")
	)
	(footprint ""
		(layer "F.Cu")
		(at 180.01488 -97.119948 -90)
		(property "Reference" "R4293"
			(at 0 0 270)
			(layer "F.SilkS")
			(hide yes)
			(effects
				(font
					(size 1.27 1.27)
				)
			)
		)
		(property "Value" ""
			(at 0 0 270)
			(layer "F.Fab")
			(effects
				(font
					(size 1.27 1.27)
				)
			)
		)
		(duplicate_pad_numbers_are_jumpers no)
		(fp_line
			(start -0.7874 0.4064)
			(end -0.7874 -0.4064)
			(stroke
				(width 0.1524)
				(type default)
			)
			(layer "F.SilkS")
		)
		(fp_line
			(start 0.7874 0.4064)
			(end -0.7874 0.4064)
			(stroke
				(width 0.1524)
				(type default)
			)
			(layer "F.SilkS")
		)
		(fp_line
			(start -0.7874 -0.4064)
			(end 0.7874 -0.4064)
			(stroke
				(width 0.1524)
				(type default)
			)
			(layer "F.SilkS")
		)
		(fp_line
			(start 0.7874 -0.4064)
			(end 0.7874 0.4064)
			(stroke
				(width 0.1524)
				(type default)
			)
			(layer "F.SilkS")
		)
		(fp_line
			(start -0.67945 0.3048)
			(end -0.67945 -0.305054)
			(stroke
				(width 0.1)
				(type default)
			)
			(layer "F.Fab")
		)
		(fp_line
			(start -0.12065 0.3048)
			(end -0.67945 0.3048)
			(stroke
				(width 0.1)
				(type default)
			)
			(layer "F.Fab")
		)
		(fp_line
			(start 0.120396 0.3048)
			(end 0.120396 0.2794)
			(stroke
				(width 0.1)
				(type default)
			)
			(layer "F.Fab")
		)
		(fp_line
			(start 0.67945 0.3048)
			(end 0.120396 0.3048)
			(stroke
				(width 0.1)
				(type default)
			)
			(layer "F.Fab")
		)
		(fp_line
			(start -0.12065 0.2794)
			(end -0.12065 0.3048)
			(stroke
				(width 0.1)
				(type default)
			)
			(layer "F.Fab")
		)
		(fp_line
			(start 0.120396 0.2794)
			(end -0.12065 0.2794)
			(stroke
				(width 0.1)
				(type default)
			)
			(layer "F.Fab")
		)
		(fp_line
			(start -0.12065 -0.2794)
			(end 0.12065 -0.2794)
			(stroke
				(width 0.1)
				(type default)
			)
			(layer "F.Fab")
		)
		(fp_line
			(start 0.12065 -0.2794)
			(end 0.12065 -0.3048)
			(stroke
				(width 0.1)
				(type default)
			)
			(layer "F.Fab")
		)
		(fp_line
			(start 0.12065 -0.3048)
			(end 0.67945 -0.3048)
			(stroke
				(width 0.1)
				(type default)
			)
			(layer "F.Fab")
		)
		(fp_line
			(start 0.67945 -0.3048)
			(end 0.67945 0.3048)
			(stroke
				(width 0.1)
				(type default)
			)
			(layer "F.Fab")
		)
		(fp_line
			(start -0.67945 -0.305054)
			(end -0.12065 -0.305054)
			(stroke
				(width 0.1)
				(type default)
			)
			(layer "F.Fab")
		)
		(fp_line
			(start -0.12065 -0.305054)
			(end -0.12065 -0.2794)
			(stroke
				(width 0.1)
				(type default)
			)
			(layer "F.Fab")
		)
		(pad "1" smd circle
			(at -0.40005 0 270)
			(size 0 0)
			(layers "F.Cu" "F.Mask" "F.Paste")
			(net "H_CPU0_MEMHOT_IN_LVC1_R1_N")
		)
		(pad "2" smd circle
			(at 0.40005 0 270)
			(size 0 0)
			(layers "F.Cu" "F.Mask" "F.Paste")
			(net "H_CPU0_MEMHOT_IN_LVC1_N")
		)
	)
	(footprint ""
		(layer "F.Cu")
		(at 211.102956 -30.276292 90)
		(property "Reference" "R3613"
			(at 0 0 90)
			(layer "F.SilkS")
			(hide yes)
			(effects
				(font
					(size 1.27 1.27)
				)
			)
		)
		(property "Value" ""
			(at 0 0 90)
			(layer "F.Fab")
			(effects
				(font
					(size 1.27 1.27)
				)
			)
		)
		(duplicate_pad_numbers_are_jumpers no)
		(fp_line
			(start 0.7874 -0.4064)
			(end 0.7874 0.4064)
			(stroke
				(width 0.1524)
				(type default)
			)
			(layer "F.SilkS")
		)
		(fp_line
			(start -0.7874 -0.4064)
			(end 0.7874 -0.4064)
			(stroke
				(width 0.1524)
				(type default)
			)
			(layer "F.SilkS")
		)
		(fp_line
			(start 0.7874 0.4064)
			(end -0.7874 0.4064)
			(stroke
				(width 0.1524)
				(type default)
			)
			(layer "F.SilkS")
		)
		(fp_line
			(start -0.7874 0.4064)
			(end -0.7874 -0.4064)
			(stroke
				(width 0.1524)
				(type default)
			)
			(layer "F.SilkS")
		)
		(fp_line
			(start -0.12065 -0.305054)
			(end -0.12065 -0.2794)
			(stroke
				(width 0.1)
				(type default)
			)
			(layer "F.Fab")
		)
		(fp_line
			(start -0.67945 -0.305054)
			(end -0.12065 -0.305054)
			(stroke
				(width 0.1)
				(type default)
			)
			(layer "F.Fab")
		)
		(fp_line
			(start 0.67945 -0.3048)
			(end 0.67945 0.3048)
			(stroke
				(width 0.1)
				(type default)
			)
			(layer "F.Fab")
		)
		(fp_line
			(start 0.12065 -0.3048)
			(end 0.67945 -0.3048)
			(stroke
				(width 0.1)
				(type default)
			)
			(layer "F.Fab")
		)
		(fp_line
			(start 0.12065 -0.2794)
			(end 0.12065 -0.3048)
			(stroke
				(width 0.1)
				(type default)
			)
			(layer "F.Fab")
		)
		(fp_line
			(start -0.12065 -0.2794)
			(end 0.12065 -0.2794)
			(stroke
				(width 0.1)
				(type default)
			)
			(layer "F.Fab")
		)
		(fp_line
			(start 0.120396 0.2794)
			(end -0.12065 0.2794)
			(stroke
				(width 0.1)
				(type default)
			)
			(layer "F.Fab")
		)
		(fp_line
			(start -0.12065 0.2794)
			(end -0.12065 0.3048)
			(stroke
				(width 0.1)
				(type default)
			)
			(layer "F.Fab")
		)
		(fp_line
			(start 0.67945 0.3048)
			(end 0.120396 0.3048)
			(stroke
				(width 0.1)
				(type default)
			)
			(layer "F.Fab")
		)
		(fp_line
			(start 0.120396 0.3048)
			(end 0.120396 0.2794)
			(stroke
				(width 0.1)
				(type default)
			)
			(layer "F.Fab")
		)
		(fp_line
			(start -0.12065 0.3048)
			(end -0.67945 0.3048)
			(stroke
				(width 0.1)
				(type default)
			)
			(layer "F.Fab")
		)
		(fp_line
			(start -0.67945 0.3048)
			(end -0.67945 -0.305054)
			(stroke
				(width 0.1)
				(type default)
			)
			(layer "F.Fab")
		)
		(pad "1" smd circle
			(at -0.40005 0 90)
			(size 0 0)
			(layers "F.Cu" "F.Mask" "F.Paste")
			(net "GND")
		)
		(pad "2" smd circle
			(at 0.40005 0 90)
			(size 0 0)
			(layers "F.Cu" "F.Mask" "F.Paste")
			(net "INA230_5_A0")
		)
	)
)
